FILE_TYPE = MACRO_DRAWING;
SET COLOR_WIRE YELLOW;
SET COLOR_PROP ORANGE;
SET COLOR_DOT WHITE;
SET COLOR_ARC YELLOW;
SET COLOR_BODY GREEN;
SET COLOR_NOTE PURPLE;
SET PROP_DISPLAY VALUE;
SET PAGE_NUMBER P43;
SET PATH_NUMBER P0;
FORCEADD QUANTA_TITLE_BLOCK_C..1
(4825 -2175);
FORCEPROP 0 LAST CDS_CON_LAST_MODIFIED Fri Aug 25 17:25:46 2023
J 0
(2940 -2160);
DISPLAY INVISIBLE (2940 -2160);
FORCEPROP 2 LAST Q_DEPT 
J 1
(1062 -2126);
DISPLAY 1.957447 (1062 -2126);
PAINT GREEN (1062 -2126);
FORCEPROP 1 LAST CUSTOM_TXT_CDS <CON_LAST_MODIFIED>
J 0
(2940 -2160);
DISPLAY 0.978723 (2940 -2160);
FORCEPROP 2 LAST CUSTOM_TXT_CDS <XR_PAGE_TITLE>
J 0
(-3065 3075);
DISPLAY 0.638298 (-3065 3075);
PAINT PINK (-3065 3075);
DISPLAY INVISIBLE (-3065 3075);
FORCEPROP 1 LAST CUSTOM_TXT_CDS <NAME_2>
J 0
(1650 -2125);
FORCEPROP 1 LAST CUSTOM_TXT_CDS <NAME_1>
J 0
(1650 -2000);
FORCEPROP 1 LAST CUSTOM_TXT_CDS <Q_NUMBER>
J 0
(3422 -2072);
DISPLAY 1.212766 (3422 -2072);
FORCEPROP 1 LAST CUSTOM_TXT_CDS <Q_PROJ>
J 0
(2443 -2073);
DISPLAY 1.212766 (2443 -2073);
FORCEPROP 1 LAST CUSTOM_TXT_CDS <Q_REV>
J 0
(4641 -2072);
DISPLAY 1.212766 (4641 -2072);
FORCEPROP 1 LAST CUSTOM_TXT_CDS <CON_PAGE_NUM> OF <CON_TOTAL_PAGES>
J 0
(4379 -2157);
DISPLAY 0.978723 (4379 -2157);
FORCEPROP 1 LAST Q_TITLE BLANK PAGE
J 0
(-4516 -2149);
DISPLAY 2.446809 (-4516 -2149);
PAINT GREEN (-4516 -2149);
FORCEPROP 1 LAST CDS_LMAN_SYM_OUTLINE -9475,6775,100,-125
J 0
(4825 -2175);
DISPLAY 0.468085 (4825 -2175);
PAINT GREEN (4825 -2175);
DISPLAY INVISIBLE (4825 -2175);
FORCEPROP 2 LAST CDS_LIB pure_quanta
J 0
(4825 -2175);
DISPLAY INVISIBLE (4825 -2175);
FORCEPROP 2 LAST PAGE_BORDER TRUE
J 0
(-3065 3075);
DISPLAY 0.638298 (-3065 3075);
PAINT PINK (-3065 3075);
DISPLAY INVISIBLE (-3065 3075);
FORCEPROP 1 LAST COMMENT_BODY TRUE
J 0
(4837 -2188);
DISPLAY 0.978723 (4837 -2188);
PAINT PEACH (4837 -2188);
DISPLAY INVISIBLE (4837 -2188);
FORCEPROP 2 LAST CDS_XR_PAGE_TITLE CR-43 : @SCM_LIB.SCM(SCH_1):PAGE43
J 0
(-3065 3075);
DISPLAY 0.638298 (-3065 3075);
PAINT PINK (-3065 3075);
DISPLAY INVISIBLE (-3065 3075);
FORCENOTE
BLANK PAGE
(-4200 925) 0;
DISPLAY LEFT (-4200 925);
DISPLAY 18.744680 (-4200 925);
QUIT
